FILE_TYPE = CONNECTIVITY;
{Allegro Design Entry HDL 16.6-p007 (v16-6-112F) 10/10/2012}
"PAGE_NUMBER" = 22;
0"NC";
1"GND\g";
2"PVCCMCP_CPU0\g";
3"P1V8_MCP_CPU0\g";
4"TP_CPU0_RSVD_267";
5"TP_CPU0_RSVD_285";
6"TP_CPU0_RSVD_282";
7"TP_CPU0_RSVD_260";
8"TP_CPU0_RSVD_270";
9"TP_CPU0_RSVD_269";
10"TP_CPU0_RSVD_263";
11"TP_CPU0_RSVD_271";
12"TP_CPU0_RSVD_273";
13"TP_CPU0_RSVD_268";
14"TP_CPU0_RSVD_283";
15"TP_CPU0_RSVD_284";
16"TP_CPU0_RSVD_286";
17"TP_CPU0_RSVD_287";
18"TP_CPU0_RSVD_288";
19"TP_CPU0_RSVD_289";
20"TP_CPU0_RSVD_290";
21"TP_CPU0_RSVD_291";
22"TP_CPU0_RSVD_292";
23"TP_CPU0_RSVD_293";
24"TP_CPU0_RSVD_298";
25"TP_CPU0_RSVD_275";
26"TP_CPU0_RSVD_274";
27"TP_CPU0_RSVD_272";
28"TP_CPU0_RSVD_276";
29"TP_CPU0_RSVD_278";
30"TP_CPU0_RSVD_280";
31"TP_CPU0_RSVD_264";
32"TP_CPU0_RSVD_262";
33"TP_CPU0_RSVD_261";
34"TP_CPU0_RSVD_277";
35"TP_CPU0_RSVD_279";
36"TP_CPU0_RSVD_281";
37"TP_CPU0_RSVD_TEST_11";
38"TP_CPU0_RSVD_242";
39"TP_CPU0_RSVD_243";
40"TP_CPU0_RSVD_244";
41"TP_CPU0_RSVD_245";
42"TP_CPU0_RSVD_246";
43"TP_CPU0_RSVD_247";
44"TP_CPU0_RSVD_249";
45"TP_CPU0_RSVD_250";
46"TP_CPU0_RSVD_251";
47"TP_CPU0_RSVD_258";
48"TP_CPU0_RSVD_259";
49"TP_CPU0_RSVD_265";
50"TP_CPU0_RSVD_266";
51"TP_CPU0_RSVD_252";
52"TP_CPU0_RSVD_253";
53"TP_CPU0_RSVD_254";
54"TP_CPU0_RSVD_256";
55"TP_CPU0_RSVD_248";
56"FM_CPU0_RC_ERROR_N";
57"TP_CPU0_RSVD_299";
58"TP_CPU0_RSVD_300";
59"TP_CPU0_RSVD_304";
60"TP_CPU0_RSVD_303";
61"TP_CPU0_RSVD_216";
62"TP_CPU0_RSVD_214";
63"TP_CPU0_RSVD_TEST_5";
64"TP_CPU0_RSVD_217";
65"TP_CPU0_RSVD_218";
66"TP_CPU0_RSVD_219";
67"TP_CPU0_RSVD_223";
68"TP_CPU0_RSVD_224";
69"TP_CPU0_RSVD_225";
70"TP_CPU0_RSVD_226";
71"TP_CPU0_RSVD_227";
72"TP_CPU0_RSVD_212";
73"TP_CPU0_RSVD_211";
74"TP_CPU0_RSVD_210";
75"TP_CPU0_RSVD_208";
76"TP_CPU0_RSVD_198";
77"TP_CPU0_RSVD_222";
78"TP_CPU0_RSVD_228";
79"TP_CPU0_RSVD_229";
80"TP_CPU0_RSVD_230";
81"TP_CPU0_RSVD_231";
82"TP_CPU0_RSVD_232";
83"TP_CPU0_RSVD_233";
84"TP_CPU0_RSVD_234";
85"TP_CPU0_RSVD_235";
86"TP_CPU0_RSVD_194";
87"TP_CPU0_RSVD_199";
88"TP_CPU0_RSVD_204";
89"TP_CPU0_RSVD_205";
90"TP_CPU0_RSVD_TEST_4";
91"TP_CPU0_RSVD_TEST_3";
92"XDP_CPU_PWR_DEBUG_N";
93"CLK_322M_OSC_CPU0_RC_DN";
94"PD_CPU0_DMIMODE_OVERRIDE";
95"H_CPU0_FIVR_FAULT_G";
96"XDP_PRESENT_N";
97"CLK_322M_OSC_CPU0_RC_DP";
98"CLK_100M_CPU0_RC_REFCLK0_DP";
99"CLK_100M_CPU0_RC_REFCLK0_DN";
100"VSENSE_P1V8MCP_CPU0_SKT_VSEN";
101"VSENSE_P1V8MCP_CPU0_SKT_VRTN";
102"PD_CPU0_RSVD_TEST_2";
103"PD_CPU0_RSVD_TEST_1";
104"TP_CPU0_RSVD_236";
105"TP_CPU0_RSVD_237";
106"TP_CPU0_RSVD_238";
107"TP_CPU0_RSVD_239";
108"TP_CPU0_RSVD_240";
109"TP_CPU0_RSVD_241";
%"RES"
"2","(-300,2775)","0","mstr_discrete","I188";
;
CDS_SEC"1"
ROOM"CPU0"
CDS_LOCATION"R5R1"
SEC"1"
CDS_LIB"mstr_discrete"
SEC_TYPE"0402"
WATTAGE"1/16W"
MATERIAL"CHIP"
PACK_TYPE"0402"
TOLERANCE"1%"
VALUE"49.9"
PART_NUMBER"G21796-047"
LOCATION"R5R1";
"A"
$PN"1"103;
"B"
$PN"2"1;
%"GND"
"1","(-300,2450)","0","mstr_symbols","I189";
;
HDL_POWER"GND"
BODY_TYPE"PLUMBING"
SIZE"1B"
CDS_LIB"mstr_symbols"
VOLTAGE"0.0V";
"A\NAC"1;
%"RES"
"2","(-575,2775)","0","mstr_discrete","I190";
;
CDS_SEC"1"
ROOM"CPU0"
CDS_LOCATION"R5P4"
SEC"1"
CDS_LIB"mstr_discrete"
SEC_TYPE"0402"
WATTAGE"1/16W"
MATERIAL"CHIP"
PACK_TYPE"0402"
TOLERANCE"1%"
VALUE"49.9"
PART_NUMBER"G21796-047"
LOCATION"R5P4";
"A"
$PN"1"102;
"B"
$PN"2"1;
%"VCC_CORE"
"1","(-1100,2325)","0","mstr_symbols","I202";
;
CDS_LIB"mstr_symbols"
HDL_POWER"PVCCMCP_CPU0";
"A"2;
%"VCC_CORE"
"1","(-7300,4475)","0","mstr_symbols","I203";
;
CDS_LIB"mstr_symbols"
HDL_POWER"P1V8_MCP_CPU0";
"A"3;
%"SKX_EXT_B"
"2","(-4150,2550)","0","chpset_lib","I204";
;
CDS_SEC"2"
ROOM"CPU0"
CDS_LOCATION"U5D1"
SEC"2"
SEC_TYPE"BGA1"
CDS_LIB"chpset_lib"
PACK_TYPE"BGA1"
MATERIAL"IC"
PART_NUMBER"TBD"
LOCATION"U5D1";
"TEST_5"
$PN"AN14"63;
"TEST_4"
$PN"AN12"90;
"TEST_3"
$PN"AM13"91;
"TEST_2"
$PN"AG46"102;
"TEST_11"
$PN"AY13"37;
"TEST_1"
$PN"AF45"103;
"RSVD<194>"
$PN"AP61"86;
"RSVD<195>"
$PN"AP27"99;
"RSVD<196>"
$PN"AP25"2;
"RSVD<197>"
$PN"AP23"2;
"RSVD<198>"
$PN"AN62"76;
"RSVD<199>"
$PN"AN60"87;
"RSVD<200>"
$PN"AN26"2;
"RSVD<201>"
$PN"AN24"2;
"RSVD<202>"
$PN"AN22"2;
"RSVD<203>"
$PN"AN18"2;
"RSVD<204>"
$PN"AM61"88;
"RSVD<205>"
$PN"AM59"89;
"RSVD<206>"
$PN"AM27"98;
"RSVD<207>"
$PN"AM25"2;
"RSVD<208>"
$PN"AM23"75;
"RSVD<209>"
$PN"AM21"2;
"RSVD<210>"
$PN"AL62"74;
"RSVD<211>"
$PN"AL60"73;
"RSVD<212>"
$PN"AL58"72;
"RSVD<213>"
$PN"AL26"93;
"RSVD<214>"
$PN"AL22"62;
"RSVD<215>"
$PN"AL20"101;
"RSVD<216>"
$PN"AK69"61;
"RSVD<217>"
$PN"AK61"64;
"RSVD<218>"
$PN"AK59"65;
"RSVD<219>"
$PN"AK57"66;
"RSVD<220>"
$PN"AK27"97;
"RSVD<221>"
$PN"AK21"100;
"RSVD<222>"
$PN"AJ70"77;
"RSVD<223>"
$PN"AJ62"67;
"RSVD<224>"
$PN"AJ60"68;
"RSVD<225>"
$PN"AJ58"69;
"RSVD<226>"
$PN"AJ56"70;
"RSVD<227>"
$PN"AJ20"71;
"RSVD<228>"
$PN"AH73"78;
"RSVD<229>"
$PN"AH71"79;
"RSVD<230>"
$PN"AH57"80;
"RSVD<231>"
$PN"AH55"81;
"RSVD<232>"
$PN"AH19"82;
"RSVD<233>"
$PN"AH15"83;
"RSVD<234>"
$PN"AG72"84;
"RSVD<235>"
$PN"AG56"85;
"RSVD<236>"
$PN"AG54"104;
"RSVD<237>"
$PN"AG52"105;
"RSVD<238>"
$PN"AG50"106;
"RSVD<239>"
$PN"AG48"107;
"RSVD<240>"
$PN"AG20"108;
"RSVD<241>"
$PN"AF71"109;
"RSVD<242>"
$PN"AF53"38;
"RSVD<243>"
$PN"AF51"39;
"RSVD<244>"
$PN"AF49"40;
"RSVD<245>"
$PN"AF47"41;
"RSVD<246>"
$PN"AF19"42;
"RSVD<247>"
$PN"AE72"43;
"RSVD<248>"
$PN"AE52"55;
"RSVD<249>"
$PN"AE50"44;
"RSVD<250>"
$PN"AE48"45;
"RSVD<251>"
$PN"AE46"46;
"RSVD<252>"
$PN"AD51"51;
"RSVD<253>"
$PN"AD49"52;
"RSVD<254>"
$PN"AD47"53;
"RSVD<256>"
$PN"Y65"54;
"RSVD<257>"
$PN"Y23"56;
"RSVD<258>"
$PN"W66"47;
"RSVD<259>"
$PN"V67"48;
"RSVD<260>"
$PN"V65"7;
"RSVD<261>"
$PN"U66"33;
"RSVD<262>"
$PN"T67"32;
"RSVD<263>"
$PN"R66"10;
"RSVD<264>"
$PN"R62"31;
"RSVD<265>"
$PN"P65"49;
"RSVD<266>"
$PN"M63"50;
"RSVD<267>"
$PN"K61"4;
"RSVD<268>"
$PN"J62"13;
"RSVD<269>"
$PN"J46"9;
"RSVD<270>"
$PN"H85"8;
"RSVD<271>"
$PN"H83"11;
"RSVD<272>"
$PN"H1"27;
"RSVD<273>"
$PN"G84"12;
"RSVD<274>"
$PN"G64"26;
"RSVD<275>"
$PN"G2"25;
"RSVD<276>"
$PN"F83"28;
"RSVD<277>"
$PN"F65"34;
"RSVD<278>"
$PN"F23"29;
"RSVD<279>"
$PN"F3"35;
"RSVD<280>"
$PN"E84"30;
"RSVD<281>"
$PN"E24"36;
"RSVD<282>"
$PN"E4"6;
"RSVD<283>"
$PN"E2"14;
"RSVD<284>"
$PN"D83"15;
"RSVD<285>"
$PN"D65"5;
"RSVD<286>"
$PN"D17"16;
"RSVD<287>"
$PN"D5"17;
"RSVD<288>"
$PN"C82"18;
"RSVD<289>"
$PN"C24"19;
"RSVD<290>"
$PN"C18"20;
"RSVD<291>"
$PN"C6"21;
"RSVD<292>"
$PN"B81"22;
"RSVD<293>"
$PN"B77"23;
"RSVD<294>"
$PN"B17"3;
"RSVD<295>"
$PN"B15"3;
"RSVD<296>"
$PN"B13"3;
"RSVD<298>"
$PN"B7"24;
"RSVD<299>"
$PN"B3"57;
"RSVD<300>"
$PN"A24"58;
"RSVD<301>"
$PN"A16"3;
"RSVD<302>"
$PN"A14"3;
"RSVD<303>"
$PN"A6"60;
"RSVD<304>"
$PN"A4"59;
"PWR_DEBUG_N"
$PN"AP17"92;
"FIVR_FAULT"
$PN"AU14"95;
"DMIMODE_OVERRIDE"
$PN"AW12"94;
"DEBUG_EN_N"
$PN"AV21"96;
END.
